(kicad_pcb
	(version 20260206)
	(generator "pcbnew")
	(generator_version "10.0")
	(general
		(thickness 1.6)
		(legacy_teardrops no)
	)
	(paper "A4")
	(title_block
		(title "04192023_DAF0TMB3IC0_F0TG_MB_C_brd_V02_OCP.brd")
		(comment 1 "Grand Teton / footprints 2035-2041 of 8354")
	)
	(layers
		(0 "F.Cu" signal "TOP")
		(4 "In1.Cu" signal "GND")
		(6 "In2.Cu" signal "IN1")
		(8 "In3.Cu" signal "GND1")
		(10 "In4.Cu" signal "IN2")
		(12 "In5.Cu" signal "GND2")
		(14 "In6.Cu" signal "IN3")
		(16 "In7.Cu" signal "GND3")
		(18 "In8.Cu" signal "VCC")
		(20 "In9.Cu" signal "VCC1")
		(22 "In10.Cu" signal "GND4")
		(24 "In11.Cu" signal "IN4")
		(26 "In12.Cu" signal "GND5")
		(28 "In13.Cu" signal "IN5")
		(30 "In14.Cu" signal "GND6")
		(32 "In15.Cu" signal "IN6")
		(34 "In16.Cu" signal "GND7")
		(2 "B.Cu" signal "BOTTOM")
		(9 "F.Adhes" user "F.Adhesive")
		(11 "B.Adhes" user "B.Adhesive")
		(13 "F.Paste" user "Package Geometry/Pastemask Top")
		(15 "B.Paste" user "Package Geometry/Pastemask Bottom")
		(5 "F.SilkS" user "Ref Des/Silkscreen Top")
		(7 "B.SilkS" user "Ref Des/Silkscreen Bottom")
		(1 "F.Mask" user "Board Geometry/Soldermask Top")
		(3 "B.Mask" user "Board Geometry/Soldermask Bottom")
		(17 "Dwgs.User" user "User.Drawings")
		(19 "Cmts.User" user "User.Comments")
		(21 "Eco1.User" user "User.Eco1")
		(23 "Eco2.User" user "User.Eco2")
		(25 "Edge.Cuts" user "Board Geometry/Outline")
		(27 "Margin" user)
		(31 "F.CrtYd" user "Package Geometry/Place Bound Top")
		(29 "B.CrtYd" user "Package Geometry/Place Bound Bottom")
		(35 "F.Fab" user "Ref Des/Assembly Top")
		(33 "B.Fab" user "Ref Des/Assembly Bottom")
	)
	(footprint ""
		(layer "F.Cu")
		(at 17.467072 -393.394184 90)
		(property "Reference" "PR6623"
			(at 0 0 90)
			(layer "F.SilkS")
			(hide yes)
			(effects
				(font
					(size 1.27 1.27)
				)
			)
		)
		(property "Value" ""
			(at 0 0 90)
			(layer "F.Fab")
			(effects
				(font
					(size 1.27 1.27)
				)
			)
		)
		(duplicate_pad_numbers_are_jumpers no)
		(fp_line
			(start 0.7874 -0.4064)
			(end 0.7874 0.4064)
			(stroke
				(width 0.1524)
				(type default)
			)
			(layer "F.SilkS")
		)
		(fp_line
			(start -0.7874 -0.4064)
			(end 0.7874 -0.4064)
			(stroke
				(width 0.1524)
				(type default)
			)
			(layer "F.SilkS")
		)
		(fp_line
			(start 0.7874 0.4064)
			(end -0.7874 0.4064)
			(stroke
				(width 0.1524)
				(type default)
			)
			(layer "F.SilkS")
		)
		(fp_line
			(start -0.7874 0.4064)
			(end -0.7874 -0.4064)
			(stroke
				(width 0.1524)
				(type default)
			)
			(layer "F.SilkS")
		)
		(fp_line
			(start -0.12065 -0.305054)
			(end -0.12065 -0.2794)
			(stroke
				(width 0.1)
				(type default)
			)
			(layer "F.Fab")
		)
		(fp_line
			(start -0.67945 -0.305054)
			(end -0.12065 -0.305054)
			(stroke
				(width 0.1)
				(type default)
			)
			(layer "F.Fab")
		)
		(fp_line
			(start 0.67945 -0.3048)
			(end 0.67945 0.3048)
			(stroke
				(width 0.1)
				(type default)
			)
			(layer "F.Fab")
		)
		(fp_line
			(start 0.12065 -0.3048)
			(end 0.67945 -0.3048)
			(stroke
				(width 0.1)
				(type default)
			)
			(layer "F.Fab")
		)
		(fp_line
			(start 0.12065 -0.2794)
			(end 0.12065 -0.3048)
			(stroke
				(width 0.1)
				(type default)
			)
			(layer "F.Fab")
		)
		(fp_line
			(start -0.12065 -0.2794)
			(end 0.12065 -0.2794)
			(stroke
				(width 0.1)
				(type default)
			)
			(layer "F.Fab")
		)
		(fp_line
			(start 0.120396 0.2794)
			(end -0.12065 0.2794)
			(stroke
				(width 0.1)
				(type default)
			)
			(layer "F.Fab")
		)
		(fp_line
			(start -0.12065 0.2794)
			(end -0.12065 0.3048)
			(stroke
				(width 0.1)
				(type default)
			)
			(layer "F.Fab")
		)
		(fp_line
			(start 0.67945 0.3048)
			(end 0.120396 0.3048)
			(stroke
				(width 0.1)
				(type default)
			)
			(layer "F.Fab")
		)
		(fp_line
			(start 0.120396 0.3048)
			(end 0.120396 0.2794)
			(stroke
				(width 0.1)
				(type default)
			)
			(layer "F.Fab")
		)
		(fp_line
			(start -0.12065 0.3048)
			(end -0.67945 0.3048)
			(stroke
				(width 0.1)
				(type default)
			)
			(layer "F.Fab")
		)
		(fp_line
			(start -0.67945 0.3048)
			(end -0.67945 -0.305054)
			(stroke
				(width 0.1)
				(type default)
			)
			(layer "F.Fab")
		)
		(pad "1" smd circle
			(at -0.40005 0 90)
			(size 0 0)
			(layers "F.Cu" "F.Mask" "F.Paste")
			(net "SW_P0V9_RETIMER_CPU1_BOOT1")
		)
		(pad "2" smd circle
			(at 0.40005 0 90)
			(size 0 0)
			(layers "F.Cu" "F.Mask" "F.Paste")
			(net "SW_P0V9_RETIMER_CPU1_BOOT1_RC")
		)
	)
	(footprint ""
		(layer "F.Cu")
		(at 37.220906 19.444716 -90)
		(property "Reference" "U25_SRM"
			(at 0 0 270)
			(layer "F.SilkS")
			(hide yes)
			(effects
				(font
					(size 1.27 1.27)
				)
			)
		)
		(property "Value" ""
			(at 0 0 270)
			(layer "F.Fab")
			(effects
				(font
					(size 1.27 1.27)
				)
			)
		)
		(duplicate_pad_numbers_are_jumpers no)
		(pad "1" smd circle
			(at 0 0 270)
			(size 0.762 0.762)
			(layers "F.Cu" "F.Mask" "F.Paste")
			(net "Net_10788")
		)
	)
	(footprint ""
		(layer "F.Cu")
		(at 105.960164 -256.505456)
		(property "Reference" "C2667"
			(at 0 0 0)
			(layer "F.SilkS")
			(hide yes)
			(effects
				(font
					(size 1.27 1.27)
				)
			)
		)
		(property "Value" ""
			(at 0 0 0)
			(layer "F.Fab")
			(effects
				(font
					(size 1.27 1.27)
				)
			)
		)
		(duplicate_pad_numbers_are_jumpers no)
		(fp_line
			(start -0.7874 -0.4064)
			(end 0.7874 -0.4064)
			(stroke
				(width 0.1524)
				(type default)
			)
			(layer "F.SilkS")
		)
		(fp_line
			(start -0.7874 0.4064)
			(end -0.7874 -0.4064)
			(stroke
				(width 0.1524)
				(type default)
			)
			(layer "F.SilkS")
		)
		(fp_line
			(start 0.7874 -0.4064)
			(end 0.7874 0.4064)
			(stroke
				(width 0.1524)
				(type default)
			)
			(layer "F.SilkS")
		)
		(fp_line
			(start 0.7874 0.4064)
			(end -0.7874 0.4064)
			(stroke
				(width 0.1524)
				(type default)
			)
			(layer "F.SilkS")
		)
		(fp_line
			(start -0.67945 -0.305054)
			(end -0.12065 -0.305054)
			(stroke
				(width 0.1)
				(type default)
			)
			(layer "F.Fab")
		)
		(fp_line
			(start -0.67945 0.3048)
			(end -0.67945 -0.305054)
			(stroke
				(width 0.1)
				(type default)
			)
			(layer "F.Fab")
		)
		(fp_line
			(start -0.12065 -0.305054)
			(end -0.12065 -0.2794)
			(stroke
				(width 0.1)
				(type default)
			)
			(layer "F.Fab")
		)
		(fp_line
			(start -0.12065 -0.2794)
			(end 0.12065 -0.2794)
			(stroke
				(width 0.1)
				(type default)
			)
			(layer "F.Fab")
		)
		(fp_line
			(start -0.12065 0.2794)
			(end -0.12065 0.3048)
			(stroke
				(width 0.1)
				(type default)
			)
			(layer "F.Fab")
		)
		(fp_line
			(start -0.12065 0.3048)
			(end -0.67945 0.3048)
			(stroke
				(width 0.1)
				(type default)
			)
			(layer "F.Fab")
		)
		(fp_line
			(start 0.120396 0.2794)
			(end -0.12065 0.2794)
			(stroke
				(width 0.1)
				(type default)
			)
			(layer "F.Fab")
		)
		(fp_line
			(start 0.120396 0.3048)
			(end 0.120396 0.2794)
			(stroke
				(width 0.1)
				(type default)
			)
			(layer "F.Fab")
		)
		(fp_line
			(start 0.12065 -0.3048)
			(end 0.67945 -0.3048)
			(stroke
				(width 0.1)
				(type default)
			)
			(layer "F.Fab")
		)
		(fp_line
			(start 0.12065 -0.2794)
			(end 0.12065 -0.3048)
			(stroke
				(width 0.1)
				(type default)
			)
			(layer "F.Fab")
		)
		(fp_line
			(start 0.67945 -0.3048)
			(end 0.67945 0.3048)
			(stroke
				(width 0.1)
				(type default)
			)
			(layer "F.Fab")
		)
		(fp_line
			(start 0.67945 0.3048)
			(end 0.120396 0.3048)
			(stroke
				(width 0.1)
				(type default)
			)
			(layer "F.Fab")
		)
		(pad "1" smd circle
			(at -0.40005 0)
			(size 0 0)
			(layers "F.Cu" "F.Mask" "F.Paste")
			(net "PVDD18_S5_P1")
		)
		(pad "2" smd circle
			(at 0.40005 0)
			(size 0 0)
			(layers "F.Cu" "F.Mask" "F.Paste")
			(net "GND")
		)
	)
	(footprint ""
		(layer "F.Cu")
		(at 56.604154 -373.03583 -90)
		(property "Reference" "C821"
			(at 0 0 270)
			(layer "F.SilkS")
			(hide yes)
			(effects
				(font
					(size 1.27 1.27)
				)
			)
		)
		(property "Value" ""
			(at 0 0 270)
			(layer "F.Fab")
			(effects
				(font
					(size 1.27 1.27)
				)
			)
		)
		(duplicate_pad_numbers_are_jumpers no)
		(fp_line
			(start -0.299974 0.150114)
			(end -0.299974 -0.150114)
			(stroke
				(width 0.1)
				(type default)
			)
			(layer "F.Fab")
		)
		(fp_line
			(start 0.299974 0.150114)
			(end -0.299974 0.150114)
			(stroke
				(width 0.1)
				(type default)
			)
			(layer "F.Fab")
		)
		(fp_line
			(start -0.299974 -0.150114)
			(end 0.299974 -0.150114)
			(stroke
				(width 0.1)
				(type default)
			)
			(layer "F.Fab")
		)
		(fp_line
			(start 0.299974 -0.150114)
			(end 0.299974 0.150114)
			(stroke
				(width 0.1)
				(type default)
			)
			(layer "F.Fab")
		)
		(pad "1" smd rect
			(at -0.2667 0 270)
			(size 0.3048 0.381)
			(layers "F.Cu" "F.Mask" "F.Paste")
			(net "P5E_CPU1_P0_TX_C_DP<8>")
		)
		(pad "2" smd rect
			(at 0.2667 0 270)
			(size 0.3048 0.381)
			(layers "F.Cu" "F.Mask" "F.Paste")
			(net "P5E_CPU1_P0_TX_DP<8>")
		)
	)
	(footprint ""
		(layer "F.Cu")
		(at 204.64526 -51.999896)
		(property "Reference" "H113"
			(at -9.058656 -6.511544 0)
			(unlocked yes)
			(layer "F.SilkS")
			(effects
				(font
					(size 0.7874 0.5842)
					(thickness 0.1524)
				)
				(justify left)
			)
		)
		(property "Value" ""
			(at 0 0 0)
			(layer "F.Fab")
			(effects
				(font
					(size 1.27 1.27)
				)
			)
		)
		(duplicate_pad_numbers_are_jumpers no)
		(fp_circle
			(center 0 0)
			(end 7.999984 0)
			(stroke
				(width 0.1524)
				(type default)
			)
			(fill no)
			(layer "F.SilkS")
		)
		(fp_circle
			(center 0 0)
			(end 7.999984 0)
			(stroke
				(width 0.1524)
				(type default)
			)
			(fill no)
			(layer "B.SilkS")
		)
		(fp_circle
			(center 0 0)
			(end 7.999984 0)
			(stroke
				(width 0.1)
				(type default)
			)
			(fill no)
			(layer "B.Fab")
		)
		(fp_circle
			(center 0 0)
			(end 7.999984 0)
			(stroke
				(width 0.1)
				(type default)
			)
			(fill no)
			(layer "F.Fab")
		)
		(pad "" np_thru_hole circle
			(at 0 0)
			(size 5.5118 5.5118)
			(drill 5.5118)
			(layers "*.Cu" "*.Mask")
			(clearance 0.381)
			(thermal_gap 0.381)
		)
		(pad "2" thru_hole circle
			(at 0 -3.999992)
			(size 0.762 0.762)
			(drill 0.5588)
			(layers "*.Cu" "*.Mask")
			(remove_unused_layers no)
			(net "GND")
			(clearance 0.1524)
			(thermal_gap 0.1524)
		)
		(pad "3" thru_hole circle
			(at -2.999994 -2.500122)
			(size 0.762 0.762)
			(drill 0.5588)
			(layers "*.Cu" "*.Mask")
			(remove_unused_layers no)
			(net "GND")
			(clearance 0.1524)
			(thermal_gap 0.1524)
		)
		(pad "4" thru_hole circle
			(at -3.999992 0)
			(size 0.762 0.762)
			(drill 0.5588)
			(layers "*.Cu" "*.Mask")
			(remove_unused_layers no)
			(net "GND")
			(clearance 0.1524)
			(thermal_gap 0.1524)
		)
		(pad "5" thru_hole circle
			(at -2.999994 2.500122)
			(size 0.762 0.762)
			(drill 0.5588)
			(layers "*.Cu" "*.Mask")
			(remove_unused_layers no)
			(net "GND")
			(clearance 0.1524)
			(thermal_gap 0.1524)
		)
		(pad "6" thru_hole circle
			(at 0 3.999992)
			(size 0.762 0.762)
			(drill 0.5588)
			(layers "*.Cu" "*.Mask")
			(remove_unused_layers no)
			(net "GND")
			(clearance 0.1524)
			(thermal_gap 0.1524)
		)
		(pad "7" thru_hole circle
			(at 2.999994 2.500122)
			(size 0.762 0.762)
			(drill 0.5588)
			(layers "*.Cu" "*.Mask")
			(remove_unused_layers no)
			(net "GND")
			(clearance 0.1524)
			(thermal_gap 0.1524)
		)
		(pad "8" thru_hole circle
			(at 3.999992 0)
			(size 0.762 0.762)
			(drill 0.5588)
			(layers "*.Cu" "*.Mask")
			(remove_unused_layers no)
			(net "GND")
			(clearance 0.1524)
			(thermal_gap 0.1524)
		)
		(pad "9" thru_hole circle
			(at 2.999994 -2.500122)
			(size 0.762 0.762)
			(drill 0.5588)
			(layers "*.Cu" "*.Mask")
			(remove_unused_layers no)
			(net "GND")
			(clearance 0.1524)
			(thermal_gap 0.1524)
		)
		(zone
			(layer "F.Cu")
			(hatch none 0.5)
			(connect_pads
				(clearance 0)
			)
			(min_thickness 0.25)
			(keepout
				(tracks not_allowed)
				(vias allowed)
				(pads allowed)
				(copperpour not_allowed)
				(footprints allowed)
			)
			(placement
				(enabled no)
				(sheetname "")
			)
			(fill
				(thermal_gap 0.5)
				(thermal_bridge_width 0.5)
				(island_removal_mode 0)
			)
			(polygon
				(pts
					(arc
						(start 204.64526 -59.99988)
						(mid 198.988417 -57.656739)
						(end 196.645276 -51.999896)
					)
					(arc
						(start 196.645276 -51.999896)
						(mid 198.988417 -46.343053)
						(end 204.64526 -43.999912)
					)
					(xy 204.64526 -46.74616) (xy 204.594206 -46.74616)
					(arc
						(start 204.593952 -46.74616)
						(mid 199.391273 -51.999896)
						(end 204.593952 -57.253632)
					)
					(xy 204.594206 -57.253632) (xy 204.64526 -57.253632)
				)
			)
		)
		(zone
			(layer "F.Cu")
			(hatch none 0.5)
			(connect_pads
				(clearance 0)
			)
			(min_thickness 0.25)
			(keepout
				(tracks not_allowed)
				(vias allowed)
				(pads allowed)
				(copperpour not_allowed)
				(footprints allowed)
			)
			(placement
				(enabled no)
				(sheetname "")
			)
			(fill
				(thermal_gap 0.5)
				(thermal_bridge_width 0.5)
				(island_removal_mode 0)
			)
			(polygon
				(pts
					(arc
						(start 204.64526 -59.99988)
						(mid 210.302103 -57.656739)
						(end 212.645244 -51.999896)
					)
					(arc
						(start 212.645244 -51.999896)
						(mid 210.302103 -46.343053)
						(end 204.64526 -43.999912)
					)
					(xy 204.64526 -46.74616) (xy 204.696314 -46.74616)
					(arc
						(start 204.696568 -46.74616)
						(mid 209.899247 -51.999896)
						(end 204.696568 -57.253632)
					)
					(xy 204.696314 -57.253632) (xy 204.64526 -57.253632)
				)
			)
		)
		(zone
			(layers "F.Cu" "B.Cu" "In1.Cu" "In2.Cu" "In3.Cu" "In4.Cu" "In5.Cu" "In6.Cu"
				"In7.Cu" "In8.Cu" "In9.Cu" "In10.Cu" "In11.Cu" "In12.Cu" "In13.Cu" "In14.Cu"
				"In15.Cu" "In16.Cu"
			)
			(hatch none 0.5)
			(connect_pads
				(clearance 0)
			)
			(min_thickness 0.25)
			(keepout
				(tracks not_allowed)
				(vias allowed)
				(pads allowed)
				(copperpour not_allowed)
				(footprints allowed)
			)
			(placement
				(enabled no)
				(sheetname "")
			)
			(fill
				(thermal_gap 0.5)
				(thermal_bridge_width 0.5)
				(island_removal_mode 0)
			)
			(polygon
				(pts
					(arc
						(start 207.92186 -51.999896)
						(mid 201.36866 -51.999896)
						(end 207.92186 -51.999896)
					)
				)
			)
		)
		(zone
			(layer "B.Cu")
			(hatch none 0.5)
			(connect_pads
				(clearance 0)
			)
			(min_thickness 0.25)
			(keepout
				(tracks not_allowed)
				(vias allowed)
				(pads allowed)
				(copperpour not_allowed)
				(footprints allowed)
			)
			(placement
				(enabled no)
				(sheetname "")
			)
			(fill
				(thermal_gap 0.5)
				(thermal_bridge_width 0.5)
				(island_removal_mode 0)
			)
			(polygon
				(pts
					(arc
						(start 204.64526 -57.507886)
						(mid 199.13727 -51.999896)
						(end 204.64526 -46.491906)
					)
					(arc
						(start 204.64526 -46.974506)
						(mid 199.61987 -51.999896)
						(end 204.64526 -57.025286)
					)
				)
			)
		)
		(zone
			(layer "B.Cu")
			(hatch none 0.5)
			(connect_pads
				(clearance 0)
			)
			(min_thickness 0.25)
			(keepout
				(tracks not_allowed)
				(vias allowed)
				(pads allowed)
				(copperpour not_allowed)
				(footprints allowed)
			)
			(placement
				(enabled no)
				(sheetname "")
			)
			(fill
				(thermal_gap 0.5)
				(thermal_bridge_width 0.5)
				(island_removal_mode 0)
			)
			(polygon
				(pts
					(arc
						(start 204.64526 -57.507886)
						(mid 210.15325 -51.999896)
						(end 204.64526 -46.491906)
					)
					(arc
						(start 204.64526 -46.974506)
						(mid 209.67065 -51.999896)
						(end 204.64526 -57.025286)
					)
				)
			)
		)
	)
	(footprint ""
		(layer "F.Cu")
		(at 78.133702 -370.57203 -90)
		(property "Reference" "C734"
			(at 0 0 270)
			(layer "F.SilkS")
			(hide yes)
			(effects
				(font
					(size 1.27 1.27)
				)
			)
		)
		(property "Value" ""
			(at 0 0 270)
			(layer "F.Fab")
			(effects
				(font
					(size 1.27 1.27)
				)
			)
		)
		(duplicate_pad_numbers_are_jumpers no)
		(fp_line
			(start -0.299974 0.150114)
			(end -0.299974 -0.150114)
			(stroke
				(width 0.1)
				(type default)
			)
			(layer "F.Fab")
		)
		(fp_line
			(start 0.299974 0.150114)
			(end -0.299974 0.150114)
			(stroke
				(width 0.1)
				(type default)
			)
			(layer "F.Fab")
		)
		(fp_line
			(start -0.299974 -0.150114)
			(end 0.299974 -0.150114)
			(stroke
				(width 0.1)
				(type default)
			)
			(layer "F.Fab")
		)
		(fp_line
			(start 0.299974 -0.150114)
			(end 0.299974 0.150114)
			(stroke
				(width 0.1)
				(type default)
			)
			(layer "F.Fab")
		)
		(pad "1" smd rect
			(at -0.2667 0 270)
			(size 0.3048 0.381)
			(layers "F.Cu" "F.Mask" "F.Paste")
			(net "P5E_CPU1_P1_TX_C_DN<3>")
		)
		(pad "2" smd rect
			(at 0.2667 0 270)
			(size 0.3048 0.381)
			(layers "F.Cu" "F.Mask" "F.Paste")
			(net "P5E_CPU1_P1_TX_DN<3>")
		)
	)
	(footprint ""
		(layer "F.Cu")
		(at 69.862446 -384.10388 180)
		(property "Reference" "R6703"
			(at 0 0 180)
			(layer "F.SilkS")
			(hide yes)
			(effects
				(font
					(size 1.27 1.27)
				)
			)
		)
		(property "Value" ""
			(at 0 0 180)
			(layer "F.Fab")
			(effects
				(font
					(size 1.27 1.27)
				)
			)
		)
		(duplicate_pad_numbers_are_jumpers no)
		(fp_line
			(start 0.7874 0.4064)
			(end -0.7874 0.4064)
			(stroke
				(width 0.1524)
				(type default)
			)
			(layer "F.SilkS")
		)
		(fp_line
			(start 0.7874 -0.4064)
			(end 0.7874 0.4064)
			(stroke
				(width 0.1524)
				(type default)
			)
			(layer "F.SilkS")
		)
		(fp_line
			(start -0.7874 0.4064)
			(end -0.7874 -0.4064)
			(stroke
				(width 0.1524)
				(type default)
			)
			(layer "F.SilkS")
		)
		(fp_line
			(start -0.7874 -0.4064)
			(end 0.7874 -0.4064)
			(stroke
				(width 0.1524)
				(type default)
			)
			(layer "F.SilkS")
		)
		(fp_line
			(start 0.67945 0.3048)
			(end 0.120396 0.3048)
			(stroke
				(width 0.1)
				(type default)
			)
			(layer "F.Fab")
		)
		(fp_line
			(start 0.67945 -0.3048)
			(end 0.67945 0.3048)
			(stroke
				(width 0.1)
				(type default)
			)
			(layer "F.Fab")
		)
		(fp_line
			(start 0.12065 -0.2794)
			(end 0.12065 -0.3048)
			(stroke
				(width 0.1)
				(type default)
			)
			(layer "F.Fab")
		)
		(fp_line
			(start 0.12065 -0.3048)
			(end 0.67945 -0.3048)
			(stroke
				(width 0.1)
				(type default)
			)
			(layer "F.Fab")
		)
		(fp_line
			(start 0.120396 0.3048)
			(end 0.120396 0.2794)
			(stroke
				(width 0.1)
				(type default)
			)
			(layer "F.Fab")
		)
		(fp_line
			(start 0.120396 0.2794)
			(end -0.12065 0.2794)
			(stroke
				(width 0.1)
				(type default)
			)
			(layer "F.Fab")
		)
		(fp_line
			(start -0.12065 0.3048)
			(end -0.67945 0.3048)
			(stroke
				(width 0.1)
				(type default)
			)
			(layer "F.Fab")
		)
		(fp_line
			(start -0.12065 0.2794)
			(end -0.12065 0.3048)
			(stroke
				(width 0.1)
				(type default)
			)
			(layer "F.Fab")
		)
		(fp_line
			(start -0.12065 -0.2794)
			(end 0.12065 -0.2794)
			(stroke
				(width 0.1)
				(type default)
			)
			(layer "F.Fab")
		)
		(fp_line
			(start -0.12065 -0.305054)
			(end -0.12065 -0.2794)
			(stroke
				(width 0.1)
				(type default)
			)
			(layer "F.Fab")
		)
		(fp_line
			(start -0.67945 0.3048)
			(end -0.67945 -0.305054)
			(stroke
				(width 0.1)
				(type default)
			)
			(layer "F.Fab")
		)
		(fp_line
			(start -0.67945 -0.305054)
			(end -0.12065 -0.305054)
			(stroke
				(width 0.1)
				(type default)
			)
			(layer "F.Fab")
		)
		(pad "1" smd rect
			(at -0.40005 0)
			(size 0.4572 0.508)
			(layers "F.Cu" "F.Mask" "F.Paste")
			(net "P1V8_CPU1_RT0_1A_1D")
		)
		(pad "2" smd rect
			(at 0.40005 0)
			(size 0.4572 0.508)
			(layers "F.Cu" "F.Mask" "F.Paste")
			(net "P1V8_CPU1_RT0_1A")
		)
	)
)
